(kicad_pcb
	(version 20260206)
	(generator "pcbnew")
	(generator_version "10.0")
	(general
		(thickness 1.6)
		(legacy_teardrops no)
	)
	(paper "A4")
	(title_block
		(title "9052_F0T_PDB_Converter_Brick_F_V03_1208_1600_OCP.brd")
		(comment 1 "Grand Teton / footprints 239-246 of 578")
	)
	(layers
		(0 "F.Cu" signal "TOP")
		(4 "In1.Cu" signal "GND")
		(6 "In2.Cu" signal "IN1")
		(8 "In3.Cu" signal "GND1")
		(10 "In4.Cu" signal "VCC")
		(12 "In5.Cu" signal "VCC1")
		(14 "In6.Cu" signal "GND2")
		(16 "In7.Cu" signal "IN2")
		(18 "In8.Cu" signal "GND3")
		(2 "B.Cu" signal "BOTTOM")
		(9 "F.Adhes" user "F.Adhesive")
		(11 "B.Adhes" user "B.Adhesive")
		(13 "F.Paste" user "Package Geometry/Pastemask Top")
		(15 "B.Paste" user "Package Geometry/Pastemask Bottom")
		(5 "F.SilkS" user "Ref Des/Silkscreen Top")
		(7 "B.SilkS" user "Ref Des/Silkscreen Bottom")
		(1 "F.Mask" user "Board Geometry/Soldermask Top")
		(3 "B.Mask" user "Board Geometry/Soldermask Bottom")
		(17 "Dwgs.User" user "User.Drawings")
		(19 "Cmts.User" user "User.Comments")
		(21 "Eco1.User" user "User.Eco1")
		(23 "Eco2.User" user "User.Eco2")
		(25 "Edge.Cuts" user "Board Geometry/Outline")
		(27 "Margin" user)
		(31 "F.CrtYd" user "Package Geometry/Place Bound Top")
		(29 "B.CrtYd" user "Package Geometry/Place Bound Bottom")
		(35 "F.Fab" user "Ref Des/Assembly Top")
		(33 "B.Fab" user "Ref Des/Assembly Bottom")
	)
	(footprint ""
		(layer "F.Cu")
		(at 291.61359 -37.061902 180)
		(property "Reference" "PC13"
			(at 0 0 180)
			(layer "F.SilkS")
			(hide yes)
			(effects
				(font
					(size 1.27 1.27)
				)
			)
		)
		(property "Value" ""
			(at 0 0 180)
			(layer "F.Fab")
			(effects
				(font
					(size 1.27 1.27)
				)
			)
		)
		(duplicate_pad_numbers_are_jumpers no)
		(fp_line
			(start 1.524 0.762)
			(end -1.524 0.762)
			(stroke
				(width 0.1524)
				(type default)
			)
			(layer "F.SilkS")
		)
		(fp_line
			(start 1.524 -0.762)
			(end 1.524 0.762)
			(stroke
				(width 0.1524)
				(type default)
			)
			(layer "F.SilkS")
		)
		(fp_line
			(start -1.524 0.762)
			(end -1.524 -0.762)
			(stroke
				(width 0.1524)
				(type default)
			)
			(layer "F.SilkS")
		)
		(fp_line
			(start -1.524 -0.762)
			(end 1.524 -0.762)
			(stroke
				(width 0.1524)
				(type default)
			)
			(layer "F.SilkS")
		)
		(fp_line
			(start 1.1049 0.724916)
			(end 1.1049 -0.724916)
			(stroke
				(width 0.1)
				(type default)
			)
			(layer "F.Fab")
		)
		(fp_line
			(start 1.1049 -0.724916)
			(end -1.1049 -0.724916)
			(stroke
				(width 0.1)
				(type default)
			)
			(layer "F.Fab")
		)
		(fp_line
			(start -1.1049 0.724916)
			(end 1.1049 0.724916)
			(stroke
				(width 0.1)
				(type default)
			)
			(layer "F.Fab")
		)
		(fp_line
			(start -1.1049 -0.724916)
			(end -1.1049 0.724916)
			(stroke
				(width 0.1)
				(type default)
			)
			(layer "F.Fab")
		)
		(pad "1" smd rect
			(at -0.889 0)
			(size 1.016 1.27)
			(layers "F.Cu" "F.Mask" "F.Paste")
			(net "P52V_HS1_DV_DT")
		)
		(pad "2" smd rect
			(at 0.889 0)
			(size 1.016 1.27)
			(layers "F.Cu" "F.Mask" "F.Paste")
			(net "GND_FIELD_SIGNAL")
		)
	)
	(footprint ""
		(layer "F.Cu")
		(at 176.784 -6.858)
		(property "Reference" "PC111"
			(at 0 0 0)
			(layer "F.SilkS")
			(hide yes)
			(effects
				(font
					(size 1.27 1.27)
				)
			)
		)
		(property "Value" ""
			(at 0 0 0)
			(layer "F.Fab")
			(effects
				(font
					(size 1.27 1.27)
				)
			)
		)
		(duplicate_pad_numbers_are_jumpers no)
		(fp_line
			(start -0.7874 -0.4064)
			(end 0.7874 -0.4064)
			(stroke
				(width 0.1524)
				(type default)
			)
			(layer "F.SilkS")
		)
		(fp_line
			(start -0.7874 0.4064)
			(end -0.7874 -0.4064)
			(stroke
				(width 0.1524)
				(type default)
			)
			(layer "F.SilkS")
		)
		(fp_line
			(start 0.7874 -0.4064)
			(end 0.7874 0.4064)
			(stroke
				(width 0.1524)
				(type default)
			)
			(layer "F.SilkS")
		)
		(fp_line
			(start 0.7874 0.4064)
			(end -0.7874 0.4064)
			(stroke
				(width 0.1524)
				(type default)
			)
			(layer "F.SilkS")
		)
		(fp_line
			(start -0.67945 -0.305054)
			(end -0.12065 -0.305054)
			(stroke
				(width 0.1)
				(type default)
			)
			(layer "F.Fab")
		)
		(fp_line
			(start -0.67945 0.3048)
			(end -0.67945 -0.305054)
			(stroke
				(width 0.1)
				(type default)
			)
			(layer "F.Fab")
		)
		(fp_line
			(start -0.12065 -0.305054)
			(end -0.12065 -0.2794)
			(stroke
				(width 0.1)
				(type default)
			)
			(layer "F.Fab")
		)
		(fp_line
			(start -0.12065 -0.2794)
			(end 0.12065 -0.2794)
			(stroke
				(width 0.1)
				(type default)
			)
			(layer "F.Fab")
		)
		(fp_line
			(start -0.12065 0.2794)
			(end -0.12065 0.3048)
			(stroke
				(width 0.1)
				(type default)
			)
			(layer "F.Fab")
		)
		(fp_line
			(start -0.12065 0.3048)
			(end -0.67945 0.3048)
			(stroke
				(width 0.1)
				(type default)
			)
			(layer "F.Fab")
		)
		(fp_line
			(start 0.120396 0.2794)
			(end -0.12065 0.2794)
			(stroke
				(width 0.1)
				(type default)
			)
			(layer "F.Fab")
		)
		(fp_line
			(start 0.120396 0.3048)
			(end 0.120396 0.2794)
			(stroke
				(width 0.1)
				(type default)
			)
			(layer "F.Fab")
		)
		(fp_line
			(start 0.12065 -0.3048)
			(end 0.67945 -0.3048)
			(stroke
				(width 0.1)
				(type default)
			)
			(layer "F.Fab")
		)
		(fp_line
			(start 0.12065 -0.2794)
			(end 0.12065 -0.3048)
			(stroke
				(width 0.1)
				(type default)
			)
			(layer "F.Fab")
		)
		(fp_line
			(start 0.67945 -0.3048)
			(end 0.67945 0.3048)
			(stroke
				(width 0.1)
				(type default)
			)
			(layer "F.Fab")
		)
		(fp_line
			(start 0.67945 0.3048)
			(end 0.120396 0.3048)
			(stroke
				(width 0.1)
				(type default)
			)
			(layer "F.Fab")
		)
		(pad "1" smd circle
			(at -0.40005 0)
			(size 0 0)
			(layers "F.Cu" "F.Mask" "F.Paste")
			(net "P3V3_AUX_FB")
		)
		(pad "2" smd circle
			(at 0.40005 0)
			(size 0 0)
			(layers "F.Cu" "F.Mask" "F.Paste")
			(net "P3V3_AUX")
		)
	)
	(footprint ""
		(layer "F.Cu")
		(at 311.410096 -101.454966)
		(property "Reference" "H24"
			(at -1.9812 -4.079748 0)
			(unlocked yes)
			(layer "B.SilkS")
			(effects
				(font
					(size 0.7874 0.5842)
					(thickness 0.1524)
				)
				(justify left mirror)
			)
		)
		(property "Value" ""
			(at 0 0 0)
			(layer "F.Fab")
			(effects
				(font
					(size 1.27 1.27)
				)
			)
		)
		(duplicate_pad_numbers_are_jumpers no)
		(pad "1" thru_hole circle
			(at 0 0)
			(size 8.001 8.001)
			(drill 4.2418)
			(layers "*.Cu" "*.Mask")
			(remove_unused_layers no)
			(net "H24_TP")
			(clearance -1.6256)
			(padstack
				(mode front_inner_back)
				(layer "Inner"
					(shape circle)
					(size 6.0198 6.0198)
					(clearance -0.635)
				)
				(layer "B.Cu"
					(shape circle)
					(size 8.001 8.001)
					(clearance -1.6256)
				)
			)
		)
		(zone
			(layers "F.Cu" "B.Cu" "In1.Cu" "In2.Cu" "In3.Cu" "In4.Cu" "In5.Cu" "In6.Cu"
				"In7.Cu" "In8.Cu"
			)
			(hatch none 0.5)
			(connect_pads
				(clearance 0)
			)
			(min_thickness 0.25)
			(keepout
				(tracks not_allowed)
				(vias allowed)
				(pads allowed)
				(copperpour not_allowed)
				(footprints allowed)
			)
			(placement
				(enabled no)
				(sheetname "")
			)
			(fill
				(thermal_gap 0.5)
				(thermal_bridge_width 0.5)
				(island_removal_mode 0)
			)
			(polygon
				(pts
					(arc
						(start 314.920122 -101.454966)
						(mid 307.90007 -101.454966)
						(end 314.920122 -101.454966)
					)
				)
			)
		)
	)
	(footprint ""
		(layer "F.Cu")
		(at 73.66 -51.943)
		(property "Reference" "PC94"
			(at 0 0 0)
			(layer "F.SilkS")
			(hide yes)
			(effects
				(font
					(size 1.27 1.27)
				)
			)
		)
		(property "Value" ""
			(at 0 0 0)
			(layer "F.Fab")
			(effects
				(font
					(size 1.27 1.27)
				)
			)
		)
		(duplicate_pad_numbers_are_jumpers no)
		(fp_line
			(start -1.524 -0.762)
			(end 1.524 -0.762)
			(stroke
				(width 0.1524)
				(type default)
			)
			(layer "F.SilkS")
		)
		(fp_line
			(start -1.524 0.762)
			(end -1.524 -0.762)
			(stroke
				(width 0.1524)
				(type default)
			)
			(layer "F.SilkS")
		)
		(fp_line
			(start 1.524 -0.762)
			(end 1.524 0.762)
			(stroke
				(width 0.1524)
				(type default)
			)
			(layer "F.SilkS")
		)
		(fp_line
			(start 1.524 0.762)
			(end -1.524 0.762)
			(stroke
				(width 0.1524)
				(type default)
			)
			(layer "F.SilkS")
		)
		(fp_line
			(start -1.1049 -0.724916)
			(end -1.1049 0.724916)
			(stroke
				(width 0.1)
				(type default)
			)
			(layer "F.Fab")
		)
		(fp_line
			(start -1.1049 0.724916)
			(end 1.1049 0.724916)
			(stroke
				(width 0.1)
				(type default)
			)
			(layer "F.Fab")
		)
		(fp_line
			(start 1.1049 -0.724916)
			(end -1.1049 -0.724916)
			(stroke
				(width 0.1)
				(type default)
			)
			(layer "F.Fab")
		)
		(fp_line
			(start 1.1049 0.724916)
			(end 1.1049 -0.724916)
			(stroke
				(width 0.1)
				(type default)
			)
			(layer "F.Fab")
		)
		(pad "1" smd rect
			(at -0.889 0 180)
			(size 1.016 1.27)
			(layers "F.Cu" "F.Mask" "F.Paste")
			(net "P12V_BRICK")
		)
		(pad "2" smd rect
			(at 0.889 0 180)
			(size 1.016 1.27)
			(layers "F.Cu" "F.Mask" "F.Paste")
			(net "GND")
		)
	)
	(footprint ""
		(layer "F.Cu")
		(at 281.94 -49.276 90)
		(property "Reference" "PR9"
			(at 0 0 90)
			(layer "F.SilkS")
			(hide yes)
			(effects
				(font
					(size 1.27 1.27)
				)
			)
		)
		(property "Value" ""
			(at 0 0 90)
			(layer "F.Fab")
			(effects
				(font
					(size 1.27 1.27)
				)
			)
		)
		(duplicate_pad_numbers_are_jumpers no)
		(fp_line
			(start 0.7874 -0.4064)
			(end 0.7874 0.4064)
			(stroke
				(width 0.1524)
				(type default)
			)
			(layer "F.SilkS")
		)
		(fp_line
			(start -0.7874 -0.4064)
			(end 0.7874 -0.4064)
			(stroke
				(width 0.1524)
				(type default)
			)
			(layer "F.SilkS")
		)
		(fp_line
			(start 0.7874 0.4064)
			(end -0.7874 0.4064)
			(stroke
				(width 0.1524)
				(type default)
			)
			(layer "F.SilkS")
		)
		(fp_line
			(start -0.7874 0.4064)
			(end -0.7874 -0.4064)
			(stroke
				(width 0.1524)
				(type default)
			)
			(layer "F.SilkS")
		)
		(fp_line
			(start -0.12065 -0.305054)
			(end -0.12065 -0.2794)
			(stroke
				(width 0.1)
				(type default)
			)
			(layer "F.Fab")
		)
		(fp_line
			(start -0.67945 -0.305054)
			(end -0.12065 -0.305054)
			(stroke
				(width 0.1)
				(type default)
			)
			(layer "F.Fab")
		)
		(fp_line
			(start 0.67945 -0.3048)
			(end 0.67945 0.3048)
			(stroke
				(width 0.1)
				(type default)
			)
			(layer "F.Fab")
		)
		(fp_line
			(start 0.12065 -0.3048)
			(end 0.67945 -0.3048)
			(stroke
				(width 0.1)
				(type default)
			)
			(layer "F.Fab")
		)
		(fp_line
			(start 0.12065 -0.2794)
			(end 0.12065 -0.3048)
			(stroke
				(width 0.1)
				(type default)
			)
			(layer "F.Fab")
		)
		(fp_line
			(start -0.12065 -0.2794)
			(end 0.12065 -0.2794)
			(stroke
				(width 0.1)
				(type default)
			)
			(layer "F.Fab")
		)
		(fp_line
			(start 0.120396 0.2794)
			(end -0.12065 0.2794)
			(stroke
				(width 0.1)
				(type default)
			)
			(layer "F.Fab")
		)
		(fp_line
			(start -0.12065 0.2794)
			(end -0.12065 0.3048)
			(stroke
				(width 0.1)
				(type default)
			)
			(layer "F.Fab")
		)
		(fp_line
			(start 0.67945 0.3048)
			(end 0.120396 0.3048)
			(stroke
				(width 0.1)
				(type default)
			)
			(layer "F.Fab")
		)
		(fp_line
			(start 0.120396 0.3048)
			(end 0.120396 0.2794)
			(stroke
				(width 0.1)
				(type default)
			)
			(layer "F.Fab")
		)
		(fp_line
			(start -0.12065 0.3048)
			(end -0.67945 0.3048)
			(stroke
				(width 0.1)
				(type default)
			)
			(layer "F.Fab")
		)
		(fp_line
			(start -0.67945 0.3048)
			(end -0.67945 -0.305054)
			(stroke
				(width 0.1)
				(type default)
			)
			(layer "F.Fab")
		)
		(pad "1" smd circle
			(at -0.40005 0 90)
			(size 0 0)
			(layers "F.Cu" "F.Mask" "F.Paste")
			(net "P52V_HS1_OV")
		)
		(pad "2" smd circle
			(at 0.40005 0 90)
			(size 0 0)
			(layers "F.Cu" "F.Mask" "F.Paste")
			(net "GND_FIELD_SIGNAL")
		)
	)
	(footprint ""
		(layer "F.Cu")
		(at 178.562 -8.128)
		(property "Reference" "PR87"
			(at 0 0 0)
			(layer "F.SilkS")
			(hide yes)
			(effects
				(font
					(size 1.27 1.27)
				)
			)
		)
		(property "Value" ""
			(at 0 0 0)
			(layer "F.Fab")
			(effects
				(font
					(size 1.27 1.27)
				)
			)
		)
		(duplicate_pad_numbers_are_jumpers no)
		(fp_line
			(start -0.7874 -0.4064)
			(end 0.7874 -0.4064)
			(stroke
				(width 0.1524)
				(type default)
			)
			(layer "F.SilkS")
		)
		(fp_line
			(start -0.7874 0.4064)
			(end -0.7874 -0.4064)
			(stroke
				(width 0.1524)
				(type default)
			)
			(layer "F.SilkS")
		)
		(fp_line
			(start 0.7874 -0.4064)
			(end 0.7874 0.4064)
			(stroke
				(width 0.1524)
				(type default)
			)
			(layer "F.SilkS")
		)
		(fp_line
			(start 0.7874 0.4064)
			(end -0.7874 0.4064)
			(stroke
				(width 0.1524)
				(type default)
			)
			(layer "F.SilkS")
		)
		(fp_line
			(start -0.67945 -0.305054)
			(end -0.12065 -0.305054)
			(stroke
				(width 0.1)
				(type default)
			)
			(layer "F.Fab")
		)
		(fp_line
			(start -0.67945 0.3048)
			(end -0.67945 -0.305054)
			(stroke
				(width 0.1)
				(type default)
			)
			(layer "F.Fab")
		)
		(fp_line
			(start -0.12065 -0.305054)
			(end -0.12065 -0.2794)
			(stroke
				(width 0.1)
				(type default)
			)
			(layer "F.Fab")
		)
		(fp_line
			(start -0.12065 -0.2794)
			(end 0.12065 -0.2794)
			(stroke
				(width 0.1)
				(type default)
			)
			(layer "F.Fab")
		)
		(fp_line
			(start -0.12065 0.2794)
			(end -0.12065 0.3048)
			(stroke
				(width 0.1)
				(type default)
			)
			(layer "F.Fab")
		)
		(fp_line
			(start -0.12065 0.3048)
			(end -0.67945 0.3048)
			(stroke
				(width 0.1)
				(type default)
			)
			(layer "F.Fab")
		)
		(fp_line
			(start 0.120396 0.2794)
			(end -0.12065 0.2794)
			(stroke
				(width 0.1)
				(type default)
			)
			(layer "F.Fab")
		)
		(fp_line
			(start 0.120396 0.3048)
			(end 0.120396 0.2794)
			(stroke
				(width 0.1)
				(type default)
			)
			(layer "F.Fab")
		)
		(fp_line
			(start 0.12065 -0.3048)
			(end 0.67945 -0.3048)
			(stroke
				(width 0.1)
				(type default)
			)
			(layer "F.Fab")
		)
		(fp_line
			(start 0.12065 -0.2794)
			(end 0.12065 -0.3048)
			(stroke
				(width 0.1)
				(type default)
			)
			(layer "F.Fab")
		)
		(fp_line
			(start 0.67945 -0.3048)
			(end 0.67945 0.3048)
			(stroke
				(width 0.1)
				(type default)
			)
			(layer "F.Fab")
		)
		(fp_line
			(start 0.67945 0.3048)
			(end 0.120396 0.3048)
			(stroke
				(width 0.1)
				(type default)
			)
			(layer "F.Fab")
		)
		(pad "1" smd circle
			(at -0.40005 0)
			(size 0 0)
			(layers "F.Cu" "F.Mask" "F.Paste")
			(net "P3V3_AUX")
		)
		(pad "2" smd circle
			(at 0.40005 0)
			(size 0 0)
			(layers "F.Cu" "F.Mask" "F.Paste")
			(net "P3V3_AUX_PWRGD")
		)
	)
	(footprint ""
		(layer "F.Cu")
		(at 109.097826 -130.175)
		(property "Reference" "PC47"
			(at 0 0 0)
			(layer "F.SilkS")
			(hide yes)
			(effects
				(font
					(size 1.27 1.27)
				)
			)
		)
		(property "Value" ""
			(at 0 0 0)
			(layer "F.Fab")
			(effects
				(font
					(size 1.27 1.27)
				)
			)
		)
		(duplicate_pad_numbers_are_jumpers no)
		(fp_line
			(start -2.2098 -0.9398)
			(end 2.2098 -0.9398)
			(stroke
				(width 0.1524)
				(type default)
			)
			(layer "F.SilkS")
		)
		(fp_line
			(start -2.2098 0.9398)
			(end -2.2098 -0.9398)
			(stroke
				(width 0.1524)
				(type default)
			)
			(layer "F.SilkS")
		)
		(fp_line
			(start 2.2098 -0.9398)
			(end 2.2098 0.9398)
			(stroke
				(width 0.1524)
				(type default)
			)
			(layer "F.SilkS")
		)
		(fp_line
			(start 2.2098 0.9398)
			(end -2.2098 0.9398)
			(stroke
				(width 0.1524)
				(type default)
			)
			(layer "F.SilkS")
		)
		(fp_line
			(start -1.700022 -0.899922)
			(end 1.700022 -0.899922)
			(stroke
				(width 0.1)
				(type default)
			)
			(layer "F.Fab")
		)
		(fp_line
			(start -1.700022 0.899922)
			(end -1.700022 -0.899922)
			(stroke
				(width 0.1)
				(type default)
			)
			(layer "F.Fab")
		)
		(fp_line
			(start 1.700022 -0.899922)
			(end 1.700022 0.899922)
			(stroke
				(width 0.1)
				(type default)
			)
			(layer "F.Fab")
		)
		(fp_line
			(start 1.700022 0.899922)
			(end -1.700022 0.899922)
			(stroke
				(width 0.1)
				(type default)
			)
			(layer "F.Fab")
		)
		(pad "1" smd rect
			(at -1.4732 0 180)
			(size 1.1684 1.5748)
			(layers "F.Cu" "F.Mask" "F.Paste")
			(net "P52V_HS_FILTER")
		)
		(pad "2" smd rect
			(at 1.4732 0 180)
			(size 1.1684 1.5748)
			(layers "F.Cu" "F.Mask" "F.Paste")
			(net "GND")
		)
	)
	(footprint ""
		(layer "F.Cu")
		(at 175.6156 -12.5222 90)
		(property "Reference" "PC102"
			(at 0 0 90)
			(layer "F.SilkS")
			(hide yes)
			(effects
				(font
					(size 1.27 1.27)
				)
			)
		)
		(property "Value" ""
			(at 0 0 90)
			(layer "F.Fab")
			(effects
				(font
					(size 1.27 1.27)
				)
			)
		)
		(duplicate_pad_numbers_are_jumpers no)
		(fp_line
			(start 0.7874 -0.4064)
			(end 0.7874 0.4064)
			(stroke
				(width 0.1524)
				(type default)
			)
			(layer "F.SilkS")
		)
		(fp_line
			(start -0.7874 -0.4064)
			(end 0.7874 -0.4064)
			(stroke
				(width 0.1524)
				(type default)
			)
			(layer "F.SilkS")
		)
		(fp_line
			(start 0.7874 0.4064)
			(end -0.7874 0.4064)
			(stroke
				(width 0.1524)
				(type default)
			)
			(layer "F.SilkS")
		)
		(fp_line
			(start -0.7874 0.4064)
			(end -0.7874 -0.4064)
			(stroke
				(width 0.1524)
				(type default)
			)
			(layer "F.SilkS")
		)
		(fp_line
			(start 0.6858 -0.3048)
			(end 0.6858 0.3048)
			(stroke
				(width 0.1)
				(type default)
			)
			(layer "F.Fab")
		)
		(fp_line
			(start 0.1016 -0.3048)
			(end 0.6858 -0.3048)
			(stroke
				(width 0.1)
				(type default)
			)
			(layer "F.Fab")
		)
		(fp_line
			(start -0.1016 -0.3048)
			(end -0.1016 -0.2794)
			(stroke
				(width 0.1)
				(type default)
			)
			(layer "F.Fab")
		)
		(fp_line
			(start -0.6858 -0.3048)
			(end -0.1016 -0.3048)
			(stroke
				(width 0.1)
				(type default)
			)
			(layer "F.Fab")
		)
		(fp_line
			(start 0.1016 -0.2794)
			(end 0.1016 -0.3048)
			(stroke
				(width 0.1)
				(type default)
			)
			(layer "F.Fab")
		)
		(fp_line
			(start -0.1016 -0.2794)
			(end 0.1016 -0.2794)
			(stroke
				(width 0.1)
				(type default)
			)
			(layer "F.Fab")
		)
		(fp_line
			(start 0.1016 0.2794)
			(end -0.1016 0.2794)
			(stroke
				(width 0.1)
				(type default)
			)
			(layer "F.Fab")
		)
		(fp_line
			(start -0.1016 0.2794)
			(end -0.1016 0.3048)
			(stroke
				(width 0.1)
				(type default)
			)
			(layer "F.Fab")
		)
		(fp_line
			(start 0.6858 0.3048)
			(end 0.1016 0.3048)
			(stroke
				(width 0.1)
				(type default)
			)
			(layer "F.Fab")
		)
		(fp_line
			(start 0.1016 0.3048)
			(end 0.1016 0.2794)
			(stroke
				(width 0.1)
				(type default)
			)
			(layer "F.Fab")
		)
		(fp_line
			(start -0.1016 0.3048)
			(end -0.6858 0.3048)
			(stroke
				(width 0.1)
				(type default)
			)
			(layer "F.Fab")
		)
		(fp_line
			(start -0.6858 0.3048)
			(end -0.6858 -0.3048)
			(stroke
				(width 0.1)
				(type default)
			)
			(layer "F.Fab")
		)
		(pad "1" smd rect
			(at -0.40005 0 270)
			(size 0.4572 0.508)
			(layers "F.Cu" "F.Mask" "F.Paste")
			(net "SW_P12V_FILT__P3V3_AUX")
		)
		(pad "2" smd rect
			(at 0.40005 0 270)
			(size 0.4572 0.508)
			(layers "F.Cu" "F.Mask" "F.Paste")
			(net "GND")
		)
	)
)
